(kicad_pcb
	(version 20241229)
	(generator "pcbnew")
	(generator_version "9.0")
	(general
		(thickness 1.552)
		(legacy_teardrops no)
	)
	(paper "A4")
	(title_block
		(date "2023-07-25")
		(rev "1.1.4")
		(comment 9 "footprints 168-172 of 379")
	)
	(layers
		(0 "F.Cu" signal)
		(4 "In1.Cu" signal)
		(6 "In2.Cu" signal)
		(8 "In3.Cu" signal)
		(10 "In4.Cu" signal)
		(12 "In5.Cu" signal)
		(14 "In6.Cu" signal)
		(2 "B.Cu" signal)
		(9 "F.Adhes" user "F.Adhesive")
		(11 "B.Adhes" user "B.Adhesive")
		(13 "F.Paste" user)
		(15 "B.Paste" user)
		(5 "F.SilkS" user "F.Silkscreen")
		(7 "B.SilkS" user "B.Silkscreen")
		(1 "F.Mask" user)
		(3 "B.Mask" user)
		(17 "Dwgs.User" user "User.Drawings")
		(19 "Cmts.User" user "User.Comments")
		(21 "Eco1.User" user "User.Eco1")
		(23 "Eco2.User" user "User.Eco2")
		(25 "Edge.Cuts" user)
		(27 "Margin" user)
		(31 "F.CrtYd" user "F.Courtyard")
		(29 "B.CrtYd" user "B.Courtyard")
		(35 "F.Fab" user)
		(33 "B.Fab" user)
	)
	(footprint "antmicro-footprints:C_0402_1005Metric"
		(layer "F.Cu")
		(at 88.5 76.4 180)
		(descr "Capacitor SMD 0402")
		(tags "capacitor SMD 0402")
		(property "Reference" "C54"
			(at 0.42 6.26 0)
			(layer "F.SilkS")
			(effects
				(font
					(size 0.65 0.65)
					(thickness 0.15)
				)
				(justify right bottom)
			)
		)
		(property "Value" "C_1u_0402"
			(at 0 1.4 0)
			(layer "F.Fab")
			(hide yes)
			(effects
				(font
					(size 0.7 0.7)
					(thickness 0.15)
				)
				(justify right bottom)
			)
		)
		(property "Datasheet" "https://product.tdk.com/en/search/capacitor/ceramic/mlcc/info?part_no=C1005X6S1A105K050BC"
			(at 0 0 180)
			(layer "F.Fab")
			(hide yes)
			(effects
				(font
					(size 1.27 1.27)
					(thickness 0.15)
				)
			)
		)
		(property "Description" "SMD Multilayer Ceramic Capacitor, 1 µF, 10 V, 0402 [1005 Metric], ± 10%, X6S, C"
			(at 0 0 180)
			(layer "F.Fab")
			(hide yes)
			(effects
				(font
					(size 1.27 1.27)
					(thickness 0.15)
				)
			)
		)
		(property "Author" "Antmicro"
			(at 177 152.8 0)
			(layer "F.Fab")
			(hide yes)
			(effects
				(font
					(size 1 1)
					(thickness 0.15)
				)
			)
		)
		(property "Dielectric" ""
			(at 177 152.8 0)
			(layer "F.Fab")
			(hide yes)
			(effects
				(font
					(size 1 1)
					(thickness 0.15)
				)
			)
		)
		(property "License" "Apache-2.0"
			(at 177 152.8 0)
			(layer "F.Fab")
			(hide yes)
			(effects
				(font
					(size 1 1)
					(thickness 0.15)
				)
			)
		)
		(property "MPN" "C1005X6S1A105K050BC"
			(at 177 152.8 0)
			(layer "F.Fab")
			(hide yes)
			(effects
				(font
					(size 1 1)
					(thickness 0.15)
				)
			)
		)
		(property "Manufacturer" "TDK"
			(at 177 152.8 0)
			(layer "F.Fab")
			(hide yes)
			(effects
				(font
					(size 1 1)
					(thickness 0.15)
				)
			)
		)
		(property "Val" "1u"
			(at 177 152.8 0)
			(layer "F.Fab")
			(hide yes)
			(effects
				(font
					(size 1 1)
					(thickness 0.15)
				)
			)
		)
		(property "Voltage" ""
			(at 177 152.8 0)
			(layer "F.Fab")
			(hide yes)
			(effects
				(font
					(size 1 1)
					(thickness 0.15)
				)
			)
		)
		(sheetname "/SDI/")
		(sheetfile "sdi.kicad_sch")
		(attr smd)
		(fp_rect
			(start -0.925 -0.47)
			(end 0.925 0.47)
			(stroke
				(width 0.05)
				(type default)
			)
			(fill no)
			(layer "F.CrtYd")
		)
		(fp_line
			(start 0.504 0.248)
			(end -0.494 0.248)
			(stroke
				(width 0.15)
				(type solid)
			)
			(layer "F.Fab")
		)
		(fp_line
			(start 0.504 -0.25)
			(end 0.504 0.248)
			(stroke
				(width 0.15)
				(type solid)
			)
			(layer "F.Fab")
		)
		(fp_line
			(start -0.494 0.248)
			(end -0.494 -0.25)
			(stroke
				(width 0.15)
				(type solid)
			)
			(layer "F.Fab")
		)
		(fp_line
			(start -0.494 -0.25)
			(end 0.504 -0.25)
			(stroke
				(width 0.15)
				(type solid)
			)
			(layer "F.Fab")
		)
		(fp_text user "Author: Antmicro"
			(at -0.939 3.399 180)
			(layer "F.Fab")
			(effects
				(font
					(size 0.7 0.7)
					(thickness 0.15)
				)
				(justify left bottom)
			)
		)
		(fp_text user "License: Apache-2.0"
			(at -0.939 5.799 180)
			(layer "F.Fab")
			(effects
				(font
					(size 0.7 0.7)
					(thickness 0.15)
				)
				(justify left bottom)
			)
		)
		(fp_text user "${REFERENCE}"
			(at -0.939 4.599 180)
			(layer "F.Fab")
			(effects
				(font
					(size 0.7 0.7)
					(thickness 0.15)
				)
				(justify left bottom)
			)
		)
		(pad "1" smd roundrect
			(at -0.48 0 180)
			(size 0.59 0.64)
			(layers "F.Cu" "F.Mask" "F.Paste")
			(roundrect_rratio 0.25)
			(net 8 "/SDI/SDI_N")
			(pintype "passive")
		)
		(pad "2" smd roundrect
			(at 0.48 0 180)
			(size 0.59 0.64)
			(layers "F.Cu" "F.Mask" "F.Paste")
			(roundrect_rratio 0.25)
			(net 293 "/SDI/SDI_N2")
			(pintype "passive")
		)
	)
	(footprint "antmicro-footprints:C_0402_1005Metric"
		(layer "F.Cu")
		(at 160.69 80.585 -90)
		(descr "Capacitor SMD 0402")
		(tags "capacitor SMD 0402")
		(property "Reference" "C113"
			(at 0.855 -0.14 90)
			(layer "F.SilkS")
			(effects
				(font
					(size 0.65 0.65)
					(thickness 0.15)
				)
				(justify right bottom)
			)
		)
		(property "Value" "C_100n_0402"
			(at 0 1.4 90)
			(layer "F.Fab")
			(hide yes)
			(effects
				(font
					(size 0.7 0.7)
					(thickness 0.15)
				)
				(justify right bottom)
			)
		)
		(property "Datasheet" "https://www.murata.com/products/productdetail?partno=GRM155R61H104KE14%23"
			(at 0 0 270)
			(layer "F.Fab")
			(hide yes)
			(effects
				(font
					(size 1.27 1.27)
					(thickness 0.15)
				)
			)
		)
		(property "Description" "SMD Multilayer Ceramic Capacitor, 0.1 µF, 50 V, 0402 [1005 Metric], ± 10%, X5R, GRM Series"
			(at 0 0 270)
			(layer "F.Fab")
			(hide yes)
			(effects
				(font
					(size 1.27 1.27)
					(thickness 0.15)
				)
			)
		)
		(property "Author" "Antmicro"
			(at 80.105 241.275 0)
			(layer "F.Fab")
			(hide yes)
			(effects
				(font
					(size 1 1)
					(thickness 0.15)
				)
			)
		)
		(property "Dielectric" "X5R"
			(at 80.105 241.275 0)
			(layer "F.Fab")
			(hide yes)
			(effects
				(font
					(size 1 1)
					(thickness 0.15)
				)
			)
		)
		(property "License" "Apache-2.0"
			(at 80.105 241.275 0)
			(layer "F.Fab")
			(hide yes)
			(effects
				(font
					(size 1 1)
					(thickness 0.15)
				)
			)
		)
		(property "MPN" "GRM155R61H104KE14D"
			(at 80.105 241.275 0)
			(layer "F.Fab")
			(hide yes)
			(effects
				(font
					(size 1 1)
					(thickness 0.15)
				)
			)
		)
		(property "Manufacturer" "Murata"
			(at 80.105 241.275 0)
			(layer "F.Fab")
			(hide yes)
			(effects
				(font
					(size 1 1)
					(thickness 0.15)
				)
			)
		)
		(property "Val" "100n"
			(at 80.105 241.275 0)
			(layer "F.Fab")
			(hide yes)
			(effects
				(font
					(size 1 1)
					(thickness 0.15)
				)
			)
		)
		(property "Voltage" "50V"
			(at 80.105 241.275 0)
			(layer "F.Fab")
			(hide yes)
			(effects
				(font
					(size 1 1)
					(thickness 0.15)
				)
			)
		)
		(sheetname "/Peripherals/")
		(sheetfile "peripherals.kicad_sch")
		(attr smd)
		(fp_rect
			(start -0.925 -0.47)
			(end 0.925 0.47)
			(stroke
				(width 0.05)
				(type default)
			)
			(fill no)
			(layer "F.CrtYd")
		)
		(fp_line
			(start -0.494 0.248)
			(end -0.494 -0.25)
			(stroke
				(width 0.15)
				(type solid)
			)
			(layer "F.Fab")
		)
		(fp_line
			(start 0.504 0.248)
			(end -0.494 0.248)
			(stroke
				(width 0.15)
				(type solid)
			)
			(layer "F.Fab")
		)
		(fp_line
			(start -0.494 -0.25)
			(end 0.504 -0.25)
			(stroke
				(width 0.15)
				(type solid)
			)
			(layer "F.Fab")
		)
		(fp_line
			(start 0.504 -0.25)
			(end 0.504 0.248)
			(stroke
				(width 0.15)
				(type solid)
			)
			(layer "F.Fab")
		)
		(fp_text user "License: Apache-2.0"
			(at -0.939 5.799 270)
			(layer "F.Fab")
			(effects
				(font
					(size 0.7 0.7)
					(thickness 0.15)
				)
				(justify left bottom)
			)
		)
		(fp_text user "${REFERENCE}"
			(at -0.939 4.599 270)
			(layer "F.Fab")
			(effects
				(font
					(size 0.7 0.7)
					(thickness 0.15)
				)
				(justify left bottom)
			)
		)
		(fp_text user "Author: Antmicro"
			(at -0.939 3.399 270)
			(layer "F.Fab")
			(effects
				(font
					(size 0.7 0.7)
					(thickness 0.15)
				)
				(justify left bottom)
			)
		)
		(pad "1" smd roundrect
			(at -0.48 0 270)
			(size 0.59 0.64)
			(layers "F.Cu" "F.Mask" "F.Paste")
			(roundrect_rratio 0.25)
			(net 1 "GND")
			(pintype "passive")
		)
		(pad "2" smd roundrect
			(at 0.48 0 270)
			(size 0.59 0.64)
			(layers "F.Cu" "F.Mask" "F.Paste")
			(roundrect_rratio 0.25)
			(net 2 "+3V3")
			(pintype "passive")
		)
	)
	(footprint "antmicro-footprints:C_0603_1608Metric"
		(layer "F.Cu")
		(at 145.21 62.52 180)
		(descr "Capacitor SMD 0603")
		(tags "capacitor 0603")
		(property "Reference" "C12"
			(at 0.51 0.5 180)
			(layer "F.SilkS")
			(effects
				(font
					(size 0.65 0.65)
					(thickness 0.15)
				)
				(justify left bottom)
			)
		)
		(property "Value" "C_10u_0603"
			(at 0 1.6 180)
			(layer "F.Fab")
			(hide yes)
			(effects
				(font
					(size 0.7 0.7)
					(thickness 0.15)
				)
				(justify left bottom)
			)
		)
		(property "Datasheet" "https://www.murata.com/products/productdetail?partno=GRM188R61A106KE69%23"
			(at 0 0 180)
			(layer "F.Fab")
			(hide yes)
			(effects
				(font
					(size 1.27 1.27)
					(thickness 0.15)
				)
			)
		)
		(property "Description" "SMD Multilayer Ceramic Capacitor, 10 µF, 10 V, 0603 [1608 Metric], ± 10%, X5R, GRM Series"
			(at 0 0 180)
			(layer "F.Fab")
			(hide yes)
			(effects
				(font
					(size 1.27 1.27)
					(thickness 0.15)
				)
			)
		)
		(property "Author" "Antmicro"
			(at 290.36 124.88 0)
			(layer "F.Fab")
			(hide yes)
			(effects
				(font
					(size 1 1)
					(thickness 0.15)
				)
			)
		)
		(property "License" "Apache-2.0"
			(at 290.36 124.88 0)
			(layer "F.Fab")
			(hide yes)
			(effects
				(font
					(size 1 1)
					(thickness 0.15)
				)
			)
		)
		(property "MPN" "GRM188R61A106KE69D"
			(at 290.36 124.88 0)
			(layer "F.Fab")
			(hide yes)
			(effects
				(font
					(size 1 1)
					(thickness 0.15)
				)
			)
		)
		(property "Manufacturer" "Murata"
			(at 290.36 124.88 0)
			(layer "F.Fab")
			(hide yes)
			(effects
				(font
					(size 1 1)
					(thickness 0.15)
				)
			)
		)
		(property "Val" "10u"
			(at 290.36 124.88 0)
			(layer "F.Fab")
			(hide yes)
			(effects
				(font
					(size 1 1)
					(thickness 0.15)
				)
			)
		)
		(property "Voltage" ""
			(at 290.36 124.88 0)
			(layer "F.Fab")
			(hide yes)
			(effects
				(font
					(size 1 1)
					(thickness 0.15)
				)
			)
		)
		(property "Dielectric" "template_dielectric"
			(at 0 0 180)
			(unlocked yes)
			(layer "F.Fab")
			(hide yes)
			(effects
				(font
					(size 1 1)
					(thickness 0.15)
				)
			)
		)
		(sheetname "/Power Supply/")
		(sheetfile "supply.kicad_sch")
		(attr smd)
		(fp_line
			(start -0.15 0.4)
			(end 0.15 0.4)
			(stroke
				(width 0.15)
				(type solid)
			)
			(layer "F.SilkS")
		)
		(fp_line
			(start -0.15 -0.4)
			(end 0.15 -0.4)
			(stroke
				(width 0.15)
				(type solid)
			)
			(layer "F.SilkS")
		)
		(fp_rect
			(start -1.25 -0.65)
			(end 1.25 0.65)
			(stroke
				(width 0.05)
				(type solid)
			)
			(fill no)
			(layer "F.CrtYd")
		)
		(fp_rect
			(start -0.8 -0.4)
			(end 0.8 0.4)
			(stroke
				(width 0.15)
				(type solid)
			)
			(fill no)
			(layer "F.Fab")
		)
		(fp_text user "${REFERENCE}"
			(at -1.682 3.895 180)
			(layer "F.Fab")
			(effects
				(font
					(size 0.7 0.7)
					(thickness 0.15)
				)
				(justify left bottom)
			)
		)
		(fp_text user "License: Apache-2.0"
			(at -1.682 5.895 180)
			(layer "F.Fab")
			(effects
				(font
					(size 0.7 0.7)
					(thickness 0.15)
				)
				(justify left bottom)
			)
		)
		(fp_text user "Author: Antmicro"
			(at -1.682 4.894 180)
			(layer "F.Fab")
			(effects
				(font
					(size 0.7 0.7)
					(thickness 0.15)
				)
				(justify left bottom)
			)
		)
		(pad "1" smd roundrect
			(at -0.7 0 180)
			(size 0.8 1)
			(layers "F.Cu" "F.Mask" "F.Paste")
			(roundrect_rratio 0.2)
			(net 327 "/Power Supply/5V_1V5_IN")
			(pintype "passive")
		)
		(pad "2" smd roundrect
			(at 0.7 0 180)
			(size 0.8 1)
			(layers "F.Cu" "F.Mask" "F.Paste")
			(roundrect_rratio 0.2)
			(net 1 "GND")
			(pintype "passive")
		)
	)
	(footprint "antmicro-footprints:R_0402_1005Metric"
		(layer "F.Cu")
		(at 110.79 100.4)
		(descr "Resistor SMD 0402")
		(tags "resistor SMD 0402")
		(property "Reference" "R78"
			(at 0.94 0.44 0)
			(layer "F.SilkS")
			(effects
				(font
					(size 0.65 0.65)
					(thickness 0.15)
				)
				(justify left bottom)
			)
		)
		(property "Value" "R_0R_0402"
			(at 0 1.4 0)
			(layer "F.Fab")
			(hide yes)
			(effects
				(font
					(size 0.7 0.7)
					(thickness 0.15)
				)
				(justify left bottom)
			)
		)
		(property "Datasheet" "https://industrial.panasonic.com/cdbs/www-data/pdf/RDA0000/AOA0000C301.pdf"
			(at 0 0 0)
			(layer "F.Fab")
			(hide yes)
			(effects
				(font
					(size 1.27 1.27)
					(thickness 0.15)
				)
			)
		)
		(property "Description" "SMD Chip Resistor, Jumper, 0 ohm, 100 mW, 0402 [1005 Metric], Thick Film, General Purpose"
			(at 0 0 0)
			(layer "F.Fab")
			(hide yes)
			(effects
				(font
					(size 1.27 1.27)
					(thickness 0.15)
				)
			)
		)
		(property "Author" "Antmicro"
			(at 0 0 0)
			(layer "F.Fab")
			(hide yes)
			(effects
				(font
					(size 1 1)
					(thickness 0.15)
				)
			)
		)
		(property "Current" "1A"
			(at 0 0 0)
			(layer "F.Fab")
			(hide yes)
			(effects
				(font
					(size 1 1)
					(thickness 0.15)
				)
			)
		)
		(property "License" "Apache-2.0"
			(at 0 0 0)
			(layer "F.Fab")
			(hide yes)
			(effects
				(font
					(size 1 1)
					(thickness 0.15)
				)
			)
		)
		(property "MPN" "ERJ2GE0R00X"
			(at 0 0 0)
			(layer "F.Fab")
			(hide yes)
			(effects
				(font
					(size 1 1)
					(thickness 0.15)
				)
			)
		)
		(property "Manufacturer" "Panasonic"
			(at 0 0 0)
			(layer "F.Fab")
			(hide yes)
			(effects
				(font
					(size 1 1)
					(thickness 0.15)
				)
			)
		)
		(property "Tolerance" "~"
			(at 0 0 0)
			(layer "F.Fab")
			(hide yes)
			(effects
				(font
					(size 1 1)
					(thickness 0.15)
				)
			)
		)
		(property "Val" "0R"
			(at 0 0 0)
			(layer "F.Fab")
			(hide yes)
			(effects
				(font
					(size 1 1)
					(thickness 0.15)
				)
			)
		)
		(sheetname "/FPGA/")
		(sheetfile "fpga.kicad_sch")
		(attr smd)
		(fp_rect
			(start -0.925 -0.47)
			(end 0.925 0.47)
			(stroke
				(width 0.05)
				(type default)
			)
			(fill no)
			(layer "F.CrtYd")
		)
		(fp_rect
			(start -0.5 -0.25)
			(end 0.5 0.25)
			(stroke
				(width 0.15)
				(type solid)
			)
			(fill no)
			(layer "F.Fab")
		)
		(fp_text user "Author: Antmicro"
			(at -0.95 4.169 0)
			(layer "F.Fab")
			(effects
				(font
					(size 0.7 0.7)
					(thickness 0.15)
				)
				(justify left bottom)
			)
		)
		(fp_text user "${REFERENCE}"
			(at -0.95 3.168 0)
			(layer "F.Fab")
			(effects
				(font
					(size 0.7 0.7)
					(thickness 0.15)
				)
				(justify left bottom)
			)
		)
		(fp_text user "License: Apache-2.0"
			(at -0.95 5.169 0)
			(layer "F.Fab")
			(effects
				(font
					(size 0.7 0.7)
					(thickness 0.15)
				)
				(justify left bottom)
			)
		)
		(pad "1" smd roundrect
			(at -0.48 0)
			(size 0.59 0.64)
			(layers "F.Cu" "F.Mask" "F.Paste")
			(roundrect_rratio 0.25)
			(net 308 "Net-(U17-A2)")
			(pintype "passive")
		)
		(pad "2" smd roundrect
			(at 0.48 0)
			(size 0.59 0.64)
			(layers "F.Cu" "F.Mask" "F.Paste")
			(roundrect_rratio 0.25)
			(net 1 "GND")
			(pintype "passive")
		)
	)
	(footprint "antmicro-footprints:R_0603_1608Metric"
		(layer "F.Cu")
		(at 165.63 116.35 90)
		(descr "Resistor SMD 0603")
		(tags "resistor SMD 0603")
		(property "Reference" "R111"
			(at 1.21 0.4 90)
			(layer "F.SilkS")
			(effects
				(font
					(size 0.65 0.65)
					(thickness 0.15)
				)
				(justify left bottom)
			)
		)
		(property "Value" "R_200R_0603"
			(at 0 1.6 90)
			(layer "F.Fab")
			(hide yes)
			(effects
				(font
					(size 0.7 0.7)
					(thickness 0.15)
				)
				(justify left bottom)
			)
		)
		(property "Datasheet" "https://www.bourns.com/docs/product-datasheets/cr.pdf"
			(at 0 0 90)
			(layer "F.Fab")
			(hide yes)
			(effects
				(font
					(size 1.27 1.27)
					(thickness 0.15)
				)
			)
		)
		(property "Description" "SMD Chip Resistor, 200 ohm, ± 1%, 100 mW, 0603 [1608 Metric], Thick Film, General Purpose"
			(at 0 0 90)
			(layer "F.Fab")
			(hide yes)
			(effects
				(font
					(size 1.27 1.27)
					(thickness 0.15)
				)
			)
		)
		(property "Author" "Antmicro"
			(at 281.98 -49.28 0)
			(layer "F.Fab")
			(hide yes)
			(effects
				(font
					(size 1 1)
					(thickness 0.15)
				)
			)
		)
		(property "License" "Apache-2.0"
			(at 281.98 -49.28 0)
			(layer "F.Fab")
			(hide yes)
			(effects
				(font
					(size 1 1)
					(thickness 0.15)
				)
			)
		)
		(property "MPN" "CR0603-FX-2000ELF"
			(at 281.98 -49.28 0)
			(layer "F.Fab")
			(hide yes)
			(effects
				(font
					(size 1 1)
					(thickness 0.15)
				)
			)
		)
		(property "Manufacturer" "Bourns"
			(at 281.98 -49.28 0)
			(layer "F.Fab")
			(hide yes)
			(effects
				(font
					(size 1 1)
					(thickness 0.15)
				)
			)
		)
		(property "Tolerance" "1%"
			(at 281.98 -49.28 0)
			(layer "F.Fab")
			(hide yes)
			(effects
				(font
					(size 1 1)
					(thickness 0.15)
				)
			)
		)
		(property "Val" "200R"
			(at 281.98 -49.28 0)
			(layer "F.Fab")
			(hide yes)
			(effects
				(font
					(size 1 1)
					(thickness 0.15)
				)
			)
		)
		(sheetname "/Peripherals/")
		(sheetfile "peripherals.kicad_sch")
		(attr smd)
		(fp_line
			(start -0.15 -0.4)
			(end 0.15 -0.4)
			(stroke
				(width 0.15)
				(type solid)
			)
			(layer "F.SilkS")
		)
		(fp_line
			(start -0.15 0.4)
			(end 0.15 0.4)
			(stroke
				(width 0.15)
				(type solid)
			)
			(layer "F.SilkS")
		)
		(fp_rect
			(start -1.25 -0.65)
			(end 1.25 0.65)
			(stroke
				(width 0.05)
				(type solid)
			)
			(fill no)
			(layer "F.CrtYd")
		)
		(fp_rect
			(start -0.8 -0.4)
			(end 0.8 0.4)
			(stroke
				(width 0.15)
				(type solid)
			)
			(fill no)
			(layer "F.Fab")
		)
		(fp_text user "${REFERENCE}"
			(at -1.25 3.898 90)
			(layer "F.Fab")
			(effects
				(font
					(size 0.7 0.7)
					(thickness 0.15)
				)
				(justify left bottom)
			)
		)
		(fp_text user "Author: Antmicro"
			(at -1.25 4.9 90)
			(layer "F.Fab")
			(effects
				(font
					(size 0.7 0.7)
					(thickness 0.15)
				)
				(justify left bottom)
			)
		)
		(fp_text user "License: Apache-2.0"
			(at -1.25 5.9 90)
			(layer "F.Fab")
			(effects
				(font
					(size 0.7 0.7)
					(thickness 0.15)
				)
				(justify left bottom)
			)
		)
		(pad "1" smd roundrect
			(at -0.7 0 90)
			(size 0.8 1)
			(layers "F.Cu" "F.Mask" "F.Paste")
			(roundrect_rratio 0.2)
			(net 63 "Net-(D3-A)")
			(pintype "passive")
		)
		(pad "2" smd roundrect
			(at 0.7 0 90)
			(size 0.8 1)
			(layers "F.Cu" "F.Mask" "F.Paste")
			(roundrect_rratio 0.2)
			(net 34 "LED1")
			(pintype "passive")
		)
	)
)
